# BASEBOARD_FAB2 (Tioga Pass) — schematic parts with pin connectivity, parts 2370–2371 of 4751; source: Cadence DE-HDL packaged netlist (pstxprt.dat, pstxnet.dat, pstchip.dat)

J4G3  SCONN288_H44441004  SCONN  pkg PIP  page 47
  1  \12v\(1)  = P12V_NVDIMM_ABC
  2  VSS(93)  GROUND  = GND
  3  DQ(4)  BI  = M_C_DQ<5>
  4  VSS(92)  GROUND  = GND
  5  DQ(0)  BI  = M_C_DQ<1>
  6  VSS(91)  GROUND  = GND
  7  DQS9P  BI  = M_C_DQS_DP<9>
  8  DQS9N  BI  = M_C_DQS_DN<9>
  9  VSS(90)  GROUND  = GND
  10  DQ(6)  BI  = M_C_DQ<7>
  11  VSS(89)  GROUND  = GND
  12  DQ(2)  BI  = M_C_DQ<3>
  13  VSS(88)  GROUND  = GND
  14  DQ(12)  BI  = M_C_DQ<13>
  15  VSS(87)  GROUND  = GND
  16  DQ(8)  BI  = M_C_DQ<9>
  17  VSS(86)  GROUND  = GND
  18  DQS10P  BI  = M_C_DQS_DP<10>
  19  DQS10N  BI  = M_C_DQS_DN<10>
  20  VSS(85)  GROUND  = GND
  21  DQ(14)  BI  = M_C_DQ<15>
  22  VSS(84)  GROUND  = GND
  23  DQ(10)  BI  = M_C_DQ<11>
  24  VSS(83)  GROUND  = GND
  25  DQ(20)  BI  = M_C_DQ<21>
  26  VSS(82)  GROUND  = GND
  27  DQ(16)  BI  = M_C_DQ<17>
  28  VSS(81)  GROUND  = GND
  29  DQS11P  BI  = M_C_DQS_DP<11>
  30  DQS11N  BI  = M_C_DQS_DN<11>
  31  VSS(80)  GROUND  = GND
  32  DQ(22)  BI  = M_C_DQ<23>
  33  VSS(79)  GROUND  = GND
  34  DQ(18)  BI  = M_C_DQ<19>
  35  VSS(78)  GROUND  = GND
  36  DQ(28)  BI  = M_C_DQ<29>
  37  VSS(77)  GROUND  = GND
  38  DQ(24)  BI  = M_C_DQ<25>
  39  VSS(76)  GROUND  = GND
  40  DQS12P  BI  = M_C_DQS_DP<12>
  41  DQS12N  BI  = M_C_DQS_DN<12>
  42  VSS(75)  GROUND  = GND
  43  DQ(30)  BI  = M_C_DQ<31>
  44  VSS(74)  GROUND  = GND
  45  DQ(26)  BI  = M_C_DQ<27>
  46  VSS(73)  GROUND  = GND
  47  CB(4)  BI  = M_C_ECC<5>
  48  VSS(72)  GROUND  = GND
  49  CB(0)  BI  = M_C_ECC<1>
  50  VSS(71)  GROUND  = GND
  51  DQS17P  BI  = M_C_DQS_DP<17>
  52  DQS17N  BI  = M_C_DQS_DN<17>
  53  VSS(70)  GROUND  = GND
  54  CB(6)  BI  = M_C_ECC<7>
  55  VSS(69)  GROUND  = GND
  56  CB(2)  BI  = M_C_ECC<3>
  57  VSS(68)  GROUND  = GND
  58  RESET_N  BI  = M_ABC_RST_N
  59  VDD(25)  POWER  = PVDDQ_ABC
  60  CKE(0)  BI  = M_C_CKE<0>
  61  VDD(24)  POWER  = PVDDQ_ABC
  62  ACT_N  BI  = M_C_ACT_N
  63  BG(0)  BI  = M_C_BG<0>
  64  VDD(23)  POWER  = PVDDQ_ABC
  65  A12  BI  = M_C_MA<12>
  66  A9  BI  = M_C_MA<9>
  67  VDD(22)  POWER  = PVDDQ_ABC
  68  A8  BI  = M_C_MA<8>
  69  A6  BI  = M_C_MA<6>
  70  VDD(21)  POWER  = PVDDQ_ABC
  71  A3  BI  = M_C_MA<3>
  72  A1  BI  = M_C_MA<1>
  73  VDD(20)  POWER  = PVDDQ_ABC
  74  CK0P  BI  = M_C_CLK_DP<0>
  75  CK0N  BI  = M_C_CLK_DN<0>
  76  VDD(19)  POWER  = PVDDQ_ABC
  77  VTT(1)  POWER  = PVTT_ABC
  78  EVENT_N  BI  = FM_DIMM_EVENT_COD_N
  79  A0  BI  = M_C_MA<0>
  80  VDD(18)  POWER  = PVDDQ_ABC
  81  BA(0)  BI  = M_C_BA<0>
  82  A16_RAS_N  BI  = M_C_MA<16>
  83  VDD(17)  POWER  = PVDDQ_ABC
  84  S0_N  BI  = M_C_CS_N<0>
  85  VDD(16)  POWER  = PVDDQ_ABC
  86  A15_CAS_N  BI  = M_C_MA<15>
  87  ODT(0)  BI  = M_C_ODT<0>
  88  VDD(15)  POWER  = PVDDQ_ABC
  89  S1_N  BI  = M_C_CS_N<1>
  90  VDD(14)  POWER  = PVDDQ_ABC
  91  ODT(1)  BI  = M_C_ODT<1>
  92  VDD(13)  POWER  = PVDDQ_ABC
  93  S2_N_C(0)  BI  = M_C_CS_N<2>
  94  VSS(67)  GROUND  = GND
  95  DQ(36)  BI  = M_C_DQ<37>
  96  VSS(66)  GROUND  = GND
  97  DQ(32)  BI  = M_C_DQ<33>
  98  VSS(65)  GROUND  = GND
  99  DQS13P  BI  = M_C_DQS_DP<13>
  100  DQS13N  BI  = M_C_DQS_DN<13>
  101  VSS(64)  GROUND  = GND
  102  DQ(38)  BI  = M_C_DQ<39>
  103  VSS(63)  GROUND  = GND
  104  DQ(34)  BI  = M_C_DQ<35>
  105  VSS(62)  GROUND  = GND
  106  DQ(44)  BI  = M_C_DQ<45>
  107  VSS(61)  GROUND  = GND
  108  DQ(40)  BI  = M_C_DQ<41>
  109  VSS(60)  GROUND  = GND
  110  DQS14P  BI  = M_C_DQS_DP<14>
  111  DQS14N  BI  = M_C_DQS_DN<14>
  112  VSS(59)  GROUND  = GND
  113  DQ(46)  BI  = M_C_DQ<47>
  114  VSS(58)  GROUND  = GND
  115  DQ(42)  BI  = M_C_DQ<43>
  116  VSS(57)  GROUND  = GND
  117  DQ(52)  BI  = M_C_DQ<53>
  118  VSS(56)  GROUND  = GND
  119  DQ(48)  BI  = M_C_DQ<49>
  120  VSS(55)  GROUND  = GND
  121  DQS15P  BI  = M_C_DQS_DP<15>
  122  DQS15N  BI  = M_C_DQS_DN<15>
  123  VSS(54)  GROUND  = GND
  124  DQ(54)  BI  = M_C_DQ<55>
  125  VSS(53)  GROUND  = GND
  126  DQ(50)  BI  = M_C_DQ<51>
  127  VSS(52)  GROUND  = GND
  128  DQ(60)  BI  = M_C_DQ<61>
  129  VSS(51)  GROUND  = GND
  130  DQ(56)  BI  = M_C_DQ<57>
  131  VSS(50)  GROUND  = GND
  132  DQS16P  BI  = M_C_DQS_DP<16>
  133  DQS16N  BI  = M_C_DQS_DN<16>
  134  VSS(49)  GROUND  = GND
  135  DQ(62)  BI  = M_C_DQ<63>
  136  VSS(48)  GROUND  = GND
  137  DQ(58)  BI  = M_C_DQ<59>
  138  VSS(47)  GROUND  = GND
  139  SA(0)  BI  = GND
  140  SA(1)  BI  = GND
  141  SCL  BI  = SMB_DDR_ABC_VPP_SCL
  142  VPP(4)  POWER  = PVPP_ABC
  143  VPP(3)  POWER  = PVPP_ABC
  144  RFU(2)  BI  = TP_CH_C_DIMM_C0_RFU_2
  145  \12v\(0)  = P12V_NVDIMM_ABC
  146  VREFCA  BI  = M_C_VREF
  147  VSS(46)  GROUND  = GND
  148  DQ(5)  BI  = M_C_DQ<4>
  149  VSS(45)  GROUND  = GND
  150  DQ(1)  BI  = M_C_DQ<0>
  151  VSS(44)  GROUND  = GND
  152  DQS0N  BI  = M_C_DQS_DN<0>
  153  DQS0P  BI  = M_C_DQS_DP<0>
  154  VSS(43)  GROUND  = GND
  155  DQ(7)  BI  = M_C_DQ<6>
  156  VSS(42)  GROUND  = GND
  157  DQ(3)  BI  = M_C_DQ<2>
  158  VSS(41)  GROUND  = GND
  159  DQ(13)  BI  = M_C_DQ<12>
  160  VSS(40)  GROUND  = GND
  161  DQ(9)  BI  = M_C_DQ<8>
  162  VSS(39)  GROUND  = GND
  163  DQS1N  BI  = M_C_DQS_DN<1>
  164  DQS1P  BI  = M_C_DQS_DP<1>
  165  VSS(38)  GROUND  = GND
  166  DQ(15)  BI  = M_C_DQ<14>
  167  VSS(37)  GROUND  = GND
  168  DQ(11)  BI  = M_C_DQ<10>
  169  VSS(36)  GROUND  = GND
  170  DQ(21)  BI  = M_C_DQ<20>
  171  VSS(35)  GROUND  = GND
  172  DQ(17)  BI  = M_C_DQ<16>
  173  VSS(34)  GROUND  = GND
  174  DQS2N  BI  = M_C_DQS_DN<2>
  175  DQS2P  BI  = M_C_DQS_DP<2>
  176  VSS(33)  GROUND  = GND
  177  DQ(23)  BI  = M_C_DQ<22>
  178  VSS(32)  GROUND  = GND
  179  DQ(19)  BI  = M_C_DQ<18>
  180  VSS(31)  GROUND  = GND
  181  DQ(29)  BI  = M_C_DQ<28>
  182  VSS(30)  GROUND  = GND
  183  DQ(25)  BI  = M_C_DQ<24>
  184  VSS(29)  GROUND  = GND
  185  DQS3N  BI  = M_C_DQS_DN<3>
  186  DQS3P  BI  = M_C_DQS_DP<3>
  187  VSS(28)  GROUND  = GND
  188  DQ(31)  BI  = M_C_DQ<30>
  189  VSS(27)  GROUND  = GND
  190  DQ(27)  BI  = M_C_DQ<26>
  191  VSS(26)  GROUND  = GND
  192  CB(5)  BI  = M_C_ECC<4>
  193  VSS(25)  GROUND  = GND
  194  CB(1)  BI  = M_C_ECC<0>
  195  VSS(24)  GROUND  = GND
  196  DQS8N  BI  = M_C_DQS_DN<8>
  197  DQS8P  BI  = M_C_DQS_DP<8>
  198  VSS(23)  GROUND  = GND
  199  CB(7)  BI  = M_C_ECC<6>
  200  VSS(22)  GROUND  = GND
  201  CB(3)  BI  = M_C_ECC<2>
  202  VSS(21)  GROUND  = GND
  203  CKE(1)  BI  = M_C_CKE<1>
  204  VDD(12)  POWER  = PVDDQ_ABC
  205  RFU(0)  BI  = TP_CH_C_DIMM_C0_RFU_0
  206  VDD(11)  POWER  = PVDDQ_ABC
  207  BG(1)  BI  = M_C_BG<1>
  208  ALERT_N  BI  = M_C_ALERT_N
  209  VDD(10)  POWER  = PVDDQ_ABC
  210  A11  BI  = M_C_MA<11>
  211  A7  BI  = M_C_MA<7>
  212  VDD(9)  POWER  = PVDDQ_ABC
  213  A5  BI  = M_C_MA<5>
  214  A4  BI  = M_C_MA<4>
  215  VDD(8)  POWER  = PVDDQ_ABC
  216  A2  BI  = M_C_MA<2>
  217  VDD(7)  POWER  = PVDDQ_ABC
  218  CK1P  BI  = M_C_CLK_DP<1>
  219  CK1N  BI  = M_C_CLK_DN<1>
  220  VDD(6)  POWER  = PVDDQ_ABC
  221  VTT(0)  POWER  = PVTT_ABC
  222  PAR  BI  = M_C_PAR
  223  VDD(5)  POWER  = PVDDQ_ABC
  224  BA(1)  BI  = M_C_BA<1>
  225  A10  BI  = M_C_MA<10>
  226  VDD(4)  POWER  = PVDDQ_ABC
  227  RFU(1)  BI  = TP_CH_C_DIMM_C0_RFU_1
  228  A14_WE_N  BI  = M_C_MA<14>
  229  VDD(3)  POWER  = PVDDQ_ABC
  230  SAVE_N_NC  BI  = FM_ADR_COMPLETE_ABC_N
  231  VDD(2)  POWER  = PVDDQ_ABC
  232  A13  BI  = M_C_MA<13>
  233  VDD(1)  POWER  = PVDDQ_ABC
  234  A17  BI  = M_C_MA<17>
  235  C(2)  BI  = M_C_C<2>
  236  VDD(0)  POWER  = PVDDQ_ABC
  237  S3_N_C(1)  BI  = M_C_CS_N<3>
  238  SA(2)  BI  = PVPP_ABC
  239  VSS(20)  GROUND  = GND
  240  DQ(37)  BI  = M_C_DQ<36>
  241  VSS(19)  GROUND  = GND
  242  DQ(33)  BI  = M_C_DQ<32>
  243  VSS(18)  GROUND  = GND
  244  DQS4N  BI  = M_C_DQS_DN<4>
  245  DQS4P  BI  = M_C_DQS_DP<4>
  246  VSS(17)  GROUND  = GND
  247  DQ(39)  BI  = M_C_DQ<38>
  248  VSS(16)  GROUND  = GND
  249  DQ(35)  BI  = M_C_DQ<34>
  250  VSS(15)  GROUND  = GND
  251  DQ(45)  BI  = M_C_DQ<44>
  252  VSS(14)  GROUND  = GND
  253  DQ(41)  BI  = M_C_DQ<40>
  254  VSS(13)  GROUND  = GND
  255  DQS5N  BI  = M_C_DQS_DN<5>
  256  DQS5P  BI  = M_C_DQS_DP<5>
  257  VSS(12)  GROUND  = GND
  258  DQ(47)  BI  = M_C_DQ<46>
  259  VSS(11)  GROUND  = GND
  260  DQ(43)  BI  = M_C_DQ<42>
  261  VSS(10)  GROUND  = GND
  262  DQ(53)  BI  = M_C_DQ<52>
  263  VSS(9)  GROUND  = GND
  264  DQ(49)  BI  = M_C_DQ<48>
  265  VSS(8)  GROUND  = GND
  266  DQS6N  BI  = M_C_DQS_DN<6>
  267  DQS6P  BI  = M_C_DQS_DP<6>
  268  VSS(7)  GROUND  = GND
  269  DQ(55)  BI  = M_C_DQ<54>
  270  VSS(6)  GROUND  = GND
  271  DQ(51)  BI  = M_C_DQ<50>
  272  VSS(5)  GROUND  = GND
  273  DQ(61)  BI  = M_C_DQ<60>
  274  VSS(4)  GROUND  = GND
  275  DQ(57)  BI  = M_C_DQ<56>
  276  VSS(3)  GROUND  = GND
  277  DQS7N  BI  = M_C_DQS_DN<7>
  278  DQS7P  BI  = M_C_DQS_DP<7>
  279  VSS(2)  GROUND  = GND
  280  DQ(63)  BI  = M_C_DQ<62>
  281  VSS(1)  GROUND  = GND
  282  DQ(59)  BI  = M_C_DQ<58>
  283  VSS(0)  GROUND  = GND
  284  VDDSPD  BI  = PVPP_ABC
  285  SDA  BI  = SMB_DDR_ABC_VPP_SDA
  286  VPP(1)  POWER  = PVPP_ABC
  287  VPP(0)  POWER  = PVPP_ABC
  288  VPP(2)  POWER  = PVPP_ABC

J6B1  SCONN120_H61426002  CONN  pkg SM  page 194
  A1  IOA1  BI  = P12V_STBY
  A2  IOA2  BI  = P12V_STBY
  A3  IOA3  BI  = P12V_STBY
  A4  IOA4  BI  = P12V_STBY
  A5  IOA5  BI  = P12V_STBY
  A6  IOA6  BI  = P12V_STBY
  A7  IOA7  BI  = P12V_STBY
  A8  IOA8  BI  = P12V_STBY
  A9  IOA9  BI  = GND
  A10  IOA10  BI  = GND
  A11  IOA11  BI  = P3V3_STBY
  A12  IOA12  BI  = GND
  A13  IOA13  BI  = P5V_STBY
  A14  IOA14  BI  = GND
  A15  IOA15  BI  = FM_P1V8MCP_CPU0_EN
  A16  IOA16  BI  = FM_PVCCIOMCP_CPU0_EN
  A17  IOA17  BI  = GND
  A18  IOA18  BI  = SMB_VR_STBY_LVC3_SCL
  A19  IOA19  BI  = SVID_ALERT0_CPU0_R_N
  A20  IOA20  BI  = SVID_CLK0_CPU0_R
  B1  IOB1  BI  = P12V_STBY
  B2  IOB2  BI  = P12V_STBY
  B3  IOB3  BI  = P12V_STBY
  B4  IOB4  BI  = P12V_STBY
  B5  IOB5  BI  = P12V_STBY
  B6  IOB6  BI  = P12V_STBY
  B7  IOB7  BI  = P12V_STBY
  B8  IOB8  BI  = P12V_STBY
  B9  IOB9  BI  = GND
  B10  IOB10  BI  = GND
  B11  IOB11  BI  = P3V3_STBY
  B12  IOB12  BI  = GND
  B13  IOB13  BI  = P5V_STBY
  B14  IOB14  BI  = GND
  B15  IOB15  BI  = PWRGD_P1V8MCP_CPU0
  B16  IOB16  BI  = PWRGD_PVCCIOMCP_CPU0
  B17  IOB17  BI  = GND
  B18  IOB18  BI  = SMB_VR_STBY_LVC3_SDA
  B19  IOB19  BI  = SVID_ALERT1_CPU0_R_N
  B20  IOB20  BI  = SVID_DIO0_CPU0_R
  C1  IOC1  BI  = GND
  C2  IOC2  BI  = GND
  C3  IOC3  BI  = GND
  C4  IOC4  BI  = GND
  C5  IOC5  BI  = GND
  C6  IOC6  BI  = GND
  C7  IOC7  BI  = GND
  C8  IOC8  BI  = GND
  C9  IOC9  BI  = GND
  C10  IOC10  BI  = GND
  C11  IOC11  BI  = P3V3_STBY
  C12  IOC12  BI  = GND
  C13  IOC13  BI  = P5V_STBY
  C14  IOC14  BI  = GND
  C15  IOC15  BI  = GND
  C16  IOC16  BI  = GND
  C17  IOC17  BI  = PVCCIOMCP_CPU0
  C18  IOC18  BI  = PVCCIOMCP_CPU0
  C19  IOC19  BI  = PVCCIOMCP_CPU0
  C20  IOC20  BI  = FM_PVCCMCP_CPU0_EN
  D1  IOD1  BI  = P3V3
  D2  IOD2  BI  = GND
  D3  IOD3  BI  = GND
  D4  IOD4  BI  = GND
  D5  IOD5  BI  = GND
  D6  IOD6  BI  = GND
  D7  IOD7  BI  = GND
  D8  IOD8  BI  = GND
  D9  IOD9  BI  = GND
  D10  IOD10  BI  = GND
  D11  IOD11  BI  = GND
  D12  IOD12  BI  = GND
  D13  IOD13  BI  = GND
  D14  IOD14  BI  = GND
  D15  IOD15  BI  = GND
  D16  IOD16  BI  = GND
  D17  IOD17  BI  = PVCCIOMCP_CPU0
  D18  IOD18  BI  = PVCCIOMCP_CPU0
  D19  IOD19  BI  = PVCCIOMCP_CPU0
  D20  IOD20  BI  = PWRGD_PVCCMCP_CPU0
  E1  IOE1  BI  = FM_CPU0_VRM_322M_156M_OSC_EN
  E2  IOE2  BI  = GND
  E3  IOE3  BI  = GND
  E4  IOE4  BI  = GND
  E5  IOE5  BI  = GND
  E6  IOE6  BI  = GND
  E7  IOE7  BI  = GND
  E8  IOE8  BI  = VSENSE_PVCCIOMCP_CPU0_SKT_VSEN
  E9  IOE9  BI  = GND
  E10  IOE10  BI  = VR_PVCCIOMCP_CPU0_XADDR1
  E11  IOE11  BI  = GND
  E12  IOE12  BI  = GND
  E13  IOE13  BI  = GND
  E14  IOE14  BI  = GND
  E15  IOE15  BI  = PVCCIOMCP_CPU0
  E16  IOE16  BI  = PVCCIOMCP_CPU0
  E17  IOE17  BI  = PVCCIOMCP_CPU0
  E18  IOE18  BI  = PVCCIOMCP_CPU0
  E19  IOE19  BI  = PVCCIOMCP_CPU0
  E20  IOE20  BI  = SVID_CLK1_CPU0_R
  F1  IOF1  BI  = PVCCIO_CPU0
  F2  IOF2  BI  = GND
  F3  IOF3  BI  = GND
  F4  IOF4  BI  = GND
  F5  IOF5  BI  = GND
  F6  IOF6  BI  = GND
  F7  IOF7  BI  = GND
  F8  IOF8  BI  = VSENSE_PVCCIOMCP_CPU0_SKT_VRTN
  F9  IOF9  BI  = GND
  F10  IOF10  BI  = VR_PVCCMCP_CPU0_XADDR2
  F11  IOF11  BI  = GND
  F12  IOF12  BI  = GND
  F13  IOF13  BI  = GND
  F14  IOF14  BI  = GND
  F15  IOF15  BI  = PVCCIOMCP_CPU0
  F16  IOF16  BI  = PVCCIOMCP_CPU0
  F17  IOF17  BI  = PVCCIOMCP_CPU0
  F18  IOF18  BI  = PVCCIOMCP_CPU0
  F19  IOF19  BI  = PVCCIOMCP_CPU0
  F20  IOF20  BI  = SVID_DIO1_CPU0_R
